(kicad_pcb
	(version 20260206)
	(generator "pcbnew")
	(generator_version "10.0")
	(general
		(thickness 1.6)
		(legacy_teardrops no)
	)
	(paper "A4")
	(title_block
		(title "peb — Lightning_PEB_BRD.brd")
		(comment 1 "Lightning (Wiwynn / Facebook NVMe JBOF) / footprints 2417-2426 of 2563")
	)
	(layers
		(0 "F.Cu" signal "TOP")
		(4 "In1.Cu" signal "L2GND")
		(6 "In2.Cu" signal "L3")
		(8 "In3.Cu" signal "L4VCC")
		(10 "In4.Cu" signal "L5VCC")
		(12 "In5.Cu" signal "L6")
		(14 "In6.Cu" signal "L7GND")
		(2 "B.Cu" signal "BOTTOM")
		(9 "F.Adhes" user "F.Adhesive")
		(11 "B.Adhes" user "B.Adhesive")
		(13 "F.Paste" user "Package Geometry/Pastemask Top")
		(15 "B.Paste" user "Package Geometry/Pastemask Bottom")
		(5 "F.SilkS" user "Ref Des/Silkscreen Top")
		(7 "B.SilkS" user "Ref Des/Silkscreen Bottom")
		(1 "F.Mask" user "Board Geometry/Soldermask Top")
		(3 "B.Mask" user "Board Geometry/Soldermask Bottom")
		(17 "Dwgs.User" user "User.Drawings")
		(19 "Cmts.User" user "User.Comments")
		(21 "Eco1.User" user "User.Eco1")
		(23 "Eco2.User" user "User.Eco2")
		(25 "Edge.Cuts" user "Board Geometry/Outline")
		(27 "Margin" user)
		(31 "F.CrtYd" user "Package Geometry/Place Bound Top")
		(29 "B.CrtYd" user "Package Geometry/Place Bound Bottom")
		(35 "F.Fab" user "Ref Des/Assembly Top")
		(33 "B.Fab" user "Ref Des/Assembly Bottom")
	)
	(footprint ""
		(layer "B.Cu")
		(at 232.537 -23.241 180)
		(property "Reference" "R789"
			(at 0 0 0)
			(layer "B.SilkS")
			(hide yes)
			(effects
				(font
					(size 1.27 1.27)
				)
				(justify mirror)
			)
		)
		(property "Value" "4K7R2F-GP"
			(at -0.064008 -3.993896 180)
			(unlocked yes)
			(layer "B.Fab")
			(hide yes)
			(effects
				(font
					(size 1.016 1.016)
					(thickness 0.1524)
				)
				(justify mirror)
			)
		)
		(property "Device Type" "R402H16"
			(at -0.064008 -5.517896 180)
			(unlocked yes)
			(layer "B.Fab")
			(hide yes)
			(effects
				(font
					(size 1.016 1.016)
					(thickness 0.1524)
				)
				(justify mirror)
			)
		)
		(duplicate_pad_numbers_are_jumpers no)
		(fp_line
			(start 0.508 -0.9398)
			(end 0.508 0.9398)
			(stroke
				(width 0.1524)
				(type default)
			)
			(layer "B.SilkS")
		)
		(fp_line
			(start -0.508 -0.9398)
			(end 0.508 -0.9398)
			(stroke
				(width 0.1524)
				(type default)
			)
			(layer "B.SilkS")
		)
		(fp_rect
			(start 0.508 0.9398)
			(end -0.508 -0.9398)
			(stroke
				(width 0)
				(type default)
			)
			(fill no)
			(layer "B.CrtYd")
		)
		(fp_rect
			(start 0.508 0.9398)
			(end -0.508 -0.9398)
			(stroke
				(width 0)
				(type default)
			)
			(fill no)
			(layer "B.Fab")
		)
		(pad "1" smd custom
			(at 0 -0.4445)
			(size 0.1397 0.1397)
			(layers "B.Cu" "B.Mask" "B.Paste")
			(net "BOOTSTRAP9")
			(options
				(clearance outline)
				(anchor circle)
			)
			(primitives
				(gr_poly
					(pts
						(arc
							(start -0.1778 0.2794)
							(mid -0.249642 0.249642)
							(end -0.2794 0.1778)
						)
						(arc
							(start -0.2794 -0.1778)
							(mid -0.249642 -0.249642)
							(end -0.1778 -0.2794)
						)
						(arc
							(start 0.1778 -0.2794)
							(mid 0.249642 -0.249642)
							(end 0.2794 -0.1778)
						)
						(arc
							(start 0.2794 0.1778)
							(mid 0.249642 0.249642)
							(end 0.1778 0.2794)
						)
					)
					(width 0)
					(fill yes)
				)
			)
		)
		(pad "2" smd custom
			(at 0 0.4445)
			(size 0.1397 0.1397)
			(layers "B.Cu" "B.Mask" "B.Paste")
			(net "BOOTSTRAP_R_9")
			(options
				(clearance outline)
				(anchor circle)
			)
			(primitives
				(gr_poly
					(pts
						(arc
							(start -0.1778 0.2794)
							(mid -0.249642 0.249642)
							(end -0.2794 0.1778)
						)
						(arc
							(start -0.2794 -0.1778)
							(mid -0.249642 -0.249642)
							(end -0.1778 -0.2794)
						)
						(arc
							(start 0.1778 -0.2794)
							(mid 0.249642 -0.249642)
							(end 0.2794 -0.1778)
						)
						(arc
							(start 0.2794 0.1778)
							(mid 0.249642 0.249642)
							(end 0.1778 0.2794)
						)
					)
					(width 0)
					(fill yes)
				)
			)
		)
	)
	(footprint ""
		(layer "B.Cu")
		(at 178.0794 -63.881)
		(property "Reference" "PG18"
			(at 0 0 0)
			(layer "B.SilkS")
			(hide yes)
			(effects
				(font
					(size 1.27 1.27)
				)
				(justify mirror)
			)
		)
		(property "Value" "GAP-CLOSE-PWR-3-GP"
			(at -0.0254 -6.5786 0)
			(unlocked yes)
			(layer "B.Fab")
			(hide yes)
			(effects
				(font
					(size 1.016 1.016)
					(thickness 0.1524)
				)
				(justify mirror)
			)
		)
		(property "Device Type" "GAP-CLOSE-PWR-3"
			(at -0.0254 -8.255 0)
			(unlocked yes)
			(layer "B.Fab")
			(hide yes)
			(effects
				(font
					(size 1.016 1.016)
					(thickness 0.1524)
				)
				(justify mirror)
			)
		)
		(duplicate_pad_numbers_are_jumpers no)
		(fp_rect
			(start 0.7112 0.4572)
			(end -0.7112 -0.4572)
			(stroke
				(width 0)
				(type default)
			)
			(fill no)
			(layer "B.CrtYd")
		)
		(fp_poly
			(pts
				(xy 0.7112 -0.4572) (xy -0.7112 -0.4572) (xy -0.7112 0.4572) (xy 0.7112 0.4572)
			)
			(stroke
				(width 0)
				(type default)
			)
			(fill no)
			(layer "B.Fab")
		)
		(pad "1" smd rect
			(at 0.3048 0 180)
			(size 0.6604 0.762)
			(layers "B.Cu" "B.Mask" "B.Paste")
			(net "DUT_AVD_PCIE")
		)
		(pad "2" smd rect
			(at -0.3048 0 180)
			(size 0.6604 0.762)
			(layers "B.Cu" "B.Mask" "B.Paste")
			(net "P0V9")
		)
	)
	(footprint ""
		(layer "B.Cu")
		(at 32.220154 -159.622744 180)
		(property "Reference" "C198"
			(at 0 0 0)
			(layer "B.SilkS")
			(hide yes)
			(effects
				(font
					(size 1.27 1.27)
				)
				(justify mirror)
			)
		)
		(property "Value" "SC1U10V2KX-4-GP"
			(at -1.1811 -2.7051 180)
			(unlocked yes)
			(layer "B.Fab")
			(hide yes)
			(effects
				(font
					(size 1.016 1.016)
					(thickness 0.1524)
				)
				(justify mirror)
			)
		)
		(property "Device Type" "C402H22"
			(at -1.1811 -4.2291 180)
			(unlocked yes)
			(layer "B.Fab")
			(hide yes)
			(effects
				(font
					(size 1.016 1.016)
					(thickness 0.1524)
				)
				(justify mirror)
			)
		)
		(duplicate_pad_numbers_are_jumpers no)
		(fp_rect
			(start 0.4318 0.9525)
			(end -0.4318 -0.9525)
			(stroke
				(width 0)
				(type default)
			)
			(fill no)
			(layer "B.CrtYd")
		)
		(fp_rect
			(start 0.4318 0.9525)
			(end -0.4318 -0.9525)
			(stroke
				(width 0)
				(type default)
			)
			(fill no)
			(layer "B.Fab")
		)
		(pad "1" smd custom
			(at 0 -0.4445)
			(size 0.1524 0.1524)
			(layers "B.Cu" "B.Mask" "B.Paste")
			(net "P1V53_STBY")
			(options
				(clearance outline)
				(anchor circle)
			)
			(primitives
				(gr_poly
					(pts
						(arc
							(start 0.3048 0.2032)
							(mid 0.275042 0.275042)
							(end 0.2032 0.3048)
						)
						(arc
							(start -0.2032 0.3048)
							(mid -0.275042 0.275042)
							(end -0.3048 0.2032)
						)
						(arc
							(start -0.3048 -0.2032)
							(mid -0.275042 -0.275042)
							(end -0.2032 -0.3048)
						)
						(arc
							(start 0.2032 -0.3048)
							(mid 0.275042 -0.275042)
							(end 0.3048 -0.2032)
						)
					)
					(width 0)
					(fill yes)
				)
			)
		)
		(pad "2" smd custom
			(at 0 0.4445)
			(size 0.1524 0.1524)
			(layers "B.Cu" "B.Mask" "B.Paste")
			(net "GND")
			(options
				(clearance outline)
				(anchor circle)
			)
			(primitives
				(gr_poly
					(pts
						(arc
							(start 0.3048 0.2032)
							(mid 0.275042 0.275042)
							(end 0.2032 0.3048)
						)
						(arc
							(start -0.2032 0.3048)
							(mid -0.275042 0.275042)
							(end -0.3048 0.2032)
						)
						(arc
							(start -0.3048 -0.2032)
							(mid -0.275042 -0.275042)
							(end -0.2032 -0.3048)
						)
						(arc
							(start 0.2032 -0.3048)
							(mid 0.275042 -0.275042)
							(end 0.3048 -0.2032)
						)
					)
					(width 0)
					(fill yes)
				)
			)
		)
	)
	(footprint ""
		(layer "B.Cu")
		(at 26.854912 -119.793512 -90)
		(property "Reference" "TP273"
			(at 0 0 90)
			(layer "B.SilkS")
			(hide yes)
			(effects
				(font
					(size 1.27 1.27)
				)
				(justify mirror)
			)
		)
		(property "Value" "TPAD28-2-GP"
			(at 0.0127 -1.6637 270)
			(unlocked yes)
			(layer "B.Fab")
			(hide yes)
			(effects
				(font
					(size 1.016 1.016)
					(thickness 0.1524)
				)
				(justify mirror)
			)
		)
		(property "Device Type" "TPAD28"
			(at 0.0127 -3.1877 270)
			(unlocked yes)
			(layer "B.Fab")
			(hide yes)
			(effects
				(font
					(size 1.016 1.016)
					(thickness 0.1524)
				)
				(justify mirror)
			)
		)
		(duplicate_pad_numbers_are_jumpers no)
		(fp_poly
			(pts
				(arc
					(start 0 -0.3556)
					(mid 0 0.3556)
					(end 0 -0.3556)
				)
			)
			(stroke
				(width 0)
				(type default)
			)
			(fill no)
			(layer "B.CrtYd")
		)
		(fp_poly
			(pts
				(arc
					(start 0 -0.6096)
					(mid 0 0.6096)
					(end 0 -0.6096)
				)
			)
			(stroke
				(width 0)
				(type default)
			)
			(fill no)
			(layer "B.Fab")
		)
		(pad "1" smd circle
			(at 0 0 90)
			(size 0.7112 0.7112)
			(layers "B.Cu" "B.Mask" "B.Paste")
			(net "TP_GPIOI2")
		)
	)
	(footprint ""
		(layer "B.Cu")
		(at 246.599964 -36.999926)
		(property "Reference" "TP282"
			(at 0 0 0)
			(layer "B.SilkS")
			(hide yes)
			(effects
				(font
					(size 1.27 1.27)
				)
				(justify mirror)
			)
		)
		(property "Value" "TPAD28-2-GP"
			(at 0.0127 -1.6637 0)
			(unlocked yes)
			(layer "B.Fab")
			(hide yes)
			(effects
				(font
					(size 1.016 1.016)
					(thickness 0.1524)
				)
				(justify mirror)
			)
		)
		(property "Device Type" "TPAD28"
			(at 0.0127 -3.1877 0)
			(unlocked yes)
			(layer "B.Fab")
			(hide yes)
			(effects
				(font
					(size 1.016 1.016)
					(thickness 0.1524)
				)
				(justify mirror)
			)
		)
		(duplicate_pad_numbers_are_jumpers no)
		(fp_poly
			(pts
				(arc
					(start 0.3556 0)
					(mid -0.3556 0)
					(end 0.3556 0)
				)
			)
			(stroke
				(width 0)
				(type default)
			)
			(fill no)
			(layer "B.CrtYd")
		)
		(fp_poly
			(pts
				(arc
					(start 0.6096 0)
					(mid -0.6096 0)
					(end 0.6096 0)
				)
			)
			(stroke
				(width 0)
				(type default)
			)
			(fill no)
			(layer "B.Fab")
		)
		(pad "1" smd circle
			(at 0 0 180)
			(size 0.7112 0.7112)
			(layers "B.Cu" "B.Mask" "B.Paste")
			(net "TWI_SRST#3")
		)
	)
	(footprint ""
		(layer "B.Cu")
		(at 228.6254 -50.995072 90)
		(property "Reference" "C562"
			(at 0 0 90)
			(layer "B.SilkS")
			(hide yes)
			(effects
				(font
					(size 1.27 1.27)
				)
				(justify mirror)
			)
		)
		(property "Value" "SCD1U16V1KX-1-GP"
			(at 2.8321 -1.7399 90)
			(unlocked yes)
			(layer "B.Fab")
			(hide yes)
			(effects
				(font
					(size 1.016 1.016)
					(thickness 0.1524)
				)
				(justify mirror)
			)
		)
		(property "Device Type" "C0201H13"
			(at 2.8321 -3.2639 90)
			(unlocked yes)
			(layer "B.Fab")
			(hide yes)
			(effects
				(font
					(size 1.016 1.016)
					(thickness 0.1524)
				)
				(justify mirror)
			)
		)
		(duplicate_pad_numbers_are_jumpers no)
		(fp_rect
			(start 0.2794 0.6477)
			(end -0.2794 -0.6477)
			(stroke
				(width 0)
				(type default)
			)
			(fill no)
			(layer "B.CrtYd")
		)
		(fp_rect
			(start 0.2794 0.6477)
			(end -0.2794 -0.6477)
			(stroke
				(width 0)
				(type default)
			)
			(fill no)
			(layer "B.Fab")
		)
		(pad "1" smd custom
			(at 0 -0.2794 270)
			(size 0.0762 0.0762)
			(layers "B.Cu" "B.Mask" "B.Paste")
			(net "DUT_AVD_PCIE")
			(options
				(clearance outline)
				(anchor circle)
			)
			(primitives
				(gr_poly
					(pts
						(arc
							(start 0.1524 0.127)
							(mid 0.137521 0.162921)
							(end 0.1016 0.1778)
						)
						(arc
							(start -0.1016 0.1778)
							(mid -0.137521 0.162921)
							(end -0.1524 0.127)
						)
						(arc
							(start -0.1524 -0.127)
							(mid -0.137521 -0.162921)
							(end -0.1016 -0.1778)
						)
						(arc
							(start 0.1016 -0.1778)
							(mid 0.137521 -0.162921)
							(end 0.1524 -0.127)
						)
					)
					(width 0)
					(fill yes)
				)
			)
		)
		(pad "2" smd custom
			(at 0 0.2794 270)
			(size 0.0762 0.0762)
			(layers "B.Cu" "B.Mask" "B.Paste")
			(net "GND")
			(options
				(clearance outline)
				(anchor circle)
			)
			(primitives
				(gr_poly
					(pts
						(arc
							(start 0.1524 0.127)
							(mid 0.137521 0.162921)
							(end 0.1016 0.1778)
						)
						(arc
							(start -0.1016 0.1778)
							(mid -0.137521 0.162921)
							(end -0.1524 0.127)
						)
						(arc
							(start -0.1524 -0.127)
							(mid -0.137521 -0.162921)
							(end -0.1016 -0.1778)
						)
						(arc
							(start 0.1016 -0.1778)
							(mid 0.137521 -0.162921)
							(end 0.1524 -0.127)
						)
					)
					(width 0)
					(fill yes)
				)
			)
		)
	)
	(footprint ""
		(layer "B.Cu")
		(at 58.039 -40.386 180)
		(property "Reference" "PR19"
			(at 0 0 0)
			(layer "B.SilkS")
			(hide yes)
			(effects
				(font
					(size 1.27 1.27)
				)
				(justify mirror)
			)
		)
		(property "Value" "2D2R3J-2-GP"
			(at 0.0254 -2.5146 180)
			(unlocked yes)
			(layer "B.Fab")
			(hide yes)
			(effects
				(font
					(size 1.016 1.016)
					(thickness 0.1524)
				)
				(justify mirror)
			)
		)
		(property "Device Type" "R603H22"
			(at 0.0254 -4.0386 180)
			(unlocked yes)
			(layer "B.Fab")
			(hide yes)
			(effects
				(font
					(size 1.016 1.016)
					(thickness 0.1524)
				)
				(justify mirror)
			)
		)
		(duplicate_pad_numbers_are_jumpers no)
		(fp_line
			(start 0.4826 0)
			(end 0.2032 0)
			(stroke
				(width 0.2032)
				(type default)
			)
			(layer "B.SilkS")
		)
		(fp_line
			(start -0.2032 0)
			(end -0.4826 0)
			(stroke
				(width 0.2032)
				(type default)
			)
			(layer "B.SilkS")
		)
		(fp_rect
			(start 0.5842 1.3335)
			(end -0.5842 -1.3335)
			(stroke
				(width 0)
				(type default)
			)
			(fill no)
			(layer "B.CrtYd")
		)
		(fp_rect
			(start 0.5842 1.3335)
			(end -0.5842 -1.3335)
			(stroke
				(width 0)
				(type default)
			)
			(fill no)
			(layer "B.Fab")
		)
		(pad "1" smd custom
			(at 0 -0.762)
			(size 0.2159 0.2159)
			(layers "B.Cu" "B.Mask" "B.Paste")
			(net "P3V3_STBY_VDD")
			(options
				(clearance outline)
				(anchor circle)
			)
			(primitives
				(gr_poly
					(pts
						(arc
							(start -0.3302 0.4318)
							(mid -0.402042 0.402042)
							(end -0.4318 0.3302)
						)
						(arc
							(start -0.4318 -0.3302)
							(mid -0.402042 -0.402042)
							(end -0.3302 -0.4318)
						)
						(arc
							(start 0.3302 -0.4318)
							(mid 0.402042 -0.402042)
							(end 0.4318 -0.3302)
						)
						(arc
							(start 0.4318 0.3302)
							(mid 0.402042 0.402042)
							(end 0.3302 0.4318)
						)
					)
					(width 0)
					(fill yes)
				)
			)
		)
		(pad "2" smd custom
			(at 0 0.762)
			(size 0.2159 0.2159)
			(layers "B.Cu" "B.Mask" "B.Paste")
			(net "P12V")
			(options
				(clearance outline)
				(anchor circle)
			)
			(primitives
				(gr_poly
					(pts
						(arc
							(start -0.3302 0.4318)
							(mid -0.402042 0.402042)
							(end -0.4318 0.3302)
						)
						(arc
							(start -0.4318 -0.3302)
							(mid -0.402042 -0.402042)
							(end -0.3302 -0.4318)
						)
						(arc
							(start 0.3302 -0.4318)
							(mid 0.402042 -0.402042)
							(end 0.4318 -0.3302)
						)
						(arc
							(start 0.4318 0.3302)
							(mid 0.402042 0.402042)
							(end 0.3302 0.4318)
						)
					)
					(width 0)
					(fill yes)
				)
			)
		)
	)
	(footprint ""
		(layer "B.Cu")
		(at 33.885632 -109.31271 90)
		(property "Reference" "R291"
			(at 0 0 90)
			(layer "B.SilkS")
			(hide yes)
			(effects
				(font
					(size 1.27 1.27)
				)
				(justify mirror)
			)
		)
		(property "Value" "0R2J-2-GP"
			(at -0.064008 -3.993896 90)
			(unlocked yes)
			(layer "B.Fab")
			(hide yes)
			(effects
				(font
					(size 1.016 1.016)
					(thickness 0.1524)
				)
				(justify mirror)
			)
		)
		(property "Device Type" "R402H16"
			(at -0.064008 -5.517896 90)
			(unlocked yes)
			(layer "B.Fab")
			(hide yes)
			(effects
				(font
					(size 1.016 1.016)
					(thickness 0.1524)
				)
				(justify mirror)
			)
		)
		(duplicate_pad_numbers_are_jumpers no)
		(fp_line
			(start 0.508 -0.9398)
			(end 0.508 0.9398)
			(stroke
				(width 0.1524)
				(type default)
			)
			(layer "B.SilkS")
		)
		(fp_line
			(start -0.508 -0.9398)
			(end 0.508 -0.9398)
			(stroke
				(width 0.1524)
				(type default)
			)
			(layer "B.SilkS")
		)
		(fp_rect
			(start 0.508 0.9398)
			(end -0.508 -0.9398)
			(stroke
				(width 0)
				(type default)
			)
			(fill no)
			(layer "B.CrtYd")
		)
		(fp_rect
			(start 0.508 0.9398)
			(end -0.508 -0.9398)
			(stroke
				(width 0)
				(type default)
			)
			(fill no)
			(layer "B.Fab")
		)
		(pad "1" smd custom
			(at 0 -0.4445 270)
			(size 0.1397 0.1397)
			(layers "B.Cu" "B.Mask" "B.Paste")
			(net "GND")
			(options
				(clearance outline)
				(anchor circle)
			)
			(primitives
				(gr_poly
					(pts
						(arc
							(start -0.1778 0.2794)
							(mid -0.249642 0.249642)
							(end -0.2794 0.1778)
						)
						(arc
							(start -0.2794 -0.1778)
							(mid -0.249642 -0.249642)
							(end -0.1778 -0.2794)
						)
						(arc
							(start 0.1778 -0.2794)
							(mid 0.249642 -0.249642)
							(end 0.2794 -0.1778)
						)
						(arc
							(start 0.2794 0.1778)
							(mid 0.249642 0.249642)
							(end 0.1778 0.2794)
						)
					)
					(width 0)
					(fill yes)
				)
			)
		)
		(pad "2" smd custom
			(at 0 0.4445 270)
			(size 0.1397 0.1397)
			(layers "B.Cu" "B.Mask" "B.Paste")
			(net "CLK_50M_BMC0")
			(options
				(clearance outline)
				(anchor circle)
			)
			(primitives
				(gr_poly
					(pts
						(arc
							(start -0.1778 0.2794)
							(mid -0.249642 0.249642)
							(end -0.2794 0.1778)
						)
						(arc
							(start -0.2794 -0.1778)
							(mid -0.249642 -0.249642)
							(end -0.1778 -0.2794)
						)
						(arc
							(start 0.1778 -0.2794)
							(mid 0.249642 -0.249642)
							(end 0.2794 -0.1778)
						)
						(arc
							(start 0.2794 0.1778)
							(mid 0.249642 0.249642)
							(end 0.1778 0.2794)
						)
					)
					(width 0)
					(fill yes)
				)
			)
		)
	)
	(footprint ""
		(layer "B.Cu")
		(at 231.6988 -28.5242)
		(property "Reference" "TP121"
			(at 0 0 0)
			(layer "B.SilkS")
			(hide yes)
			(effects
				(font
					(size 1.27 1.27)
				)
				(justify mirror)
			)
		)
		(property "Value" "TPAD28-2-GP"
			(at 0.0127 -1.6637 0)
			(unlocked yes)
			(layer "B.Fab")
			(hide yes)
			(effects
				(font
					(size 1.016 1.016)
					(thickness 0.1524)
				)
				(justify mirror)
			)
		)
		(property "Device Type" "TPAD28"
			(at 0.0127 -3.1877 0)
			(unlocked yes)
			(layer "B.Fab")
			(hide yes)
			(effects
				(font
					(size 1.016 1.016)
					(thickness 0.1524)
				)
				(justify mirror)
			)
		)
		(duplicate_pad_numbers_are_jumpers no)
		(fp_poly
			(pts
				(arc
					(start 0.3556 0)
					(mid -0.3556 0)
					(end 0.3556 0)
				)
			)
			(stroke
				(width 0)
				(type default)
			)
			(fill no)
			(layer "B.CrtYd")
		)
		(fp_poly
			(pts
				(arc
					(start 0.6096 0)
					(mid -0.6096 0)
					(end 0.6096 0)
				)
			)
			(stroke
				(width 0)
				(type default)
			)
			(fill no)
			(layer "B.Fab")
		)
		(pad "1" smd circle
			(at 0 0 180)
			(size 0.7112 0.7112)
			(layers "B.Cu" "B.Mask" "B.Paste")
			(net "LBI_ADDR_9")
		)
	)
	(footprint ""
		(layer "B.Cu")
		(at 232.6005 -36.9951 90)
		(property "Reference" "TP202"
			(at 0 0 90)
			(layer "B.SilkS")
			(hide yes)
			(effects
				(font
					(size 1.27 1.27)
				)
				(justify mirror)
			)
		)
		(property "Value" "TPAD28-2-GP"
			(at 0.0127 -1.6637 90)
			(unlocked yes)
			(layer "B.Fab")
			(hide yes)
			(effects
				(font
					(size 1.016 1.016)
					(thickness 0.1524)
				)
				(justify mirror)
			)
		)
		(property "Device Type" "TPAD28"
			(at 0.0127 -3.1877 90)
			(unlocked yes)
			(layer "B.Fab")
			(hide yes)
			(effects
				(font
					(size 1.016 1.016)
					(thickness 0.1524)
				)
				(justify mirror)
			)
		)
		(duplicate_pad_numbers_are_jumpers no)
		(fp_poly
			(pts
				(arc
					(start 0 0.3556)
					(mid 0 -0.3556)
					(end 0 0.3556)
				)
			)
			(stroke
				(width 0)
				(type default)
			)
			(fill no)
			(layer "B.CrtYd")
		)
		(fp_poly
			(pts
				(arc
					(start 0 0.6096)
					(mid 0 -0.6096)
					(end 0 0.6096)
				)
			)
			(stroke
				(width 0)
				(type default)
			)
			(fill no)
			(layer "B.Fab")
		)
		(pad "1" smd circle
			(at 0 0 270)
			(size 0.7112 0.7112)
			(layers "B.Cu" "B.Mask" "B.Paste")
			(net "RMII_RXD_0")
		)
	)
)
